(kicad_pcb
	(version 20241229)
	(generator "pcbnew")
	(generator_version "9.0")
	(general
		(thickness 1.711)
		(legacy_teardrops no)
	)
	(paper "A4")
	(title_block
		(title "Antmicro Baseboard for Jetson AGX Thor")
		(date "2026-02-18")
		(rev "1.1.0")
		(company "Antmicro Ltd")
		(comment 1 "www.antmicro.com")
		(comment 9 "footprints 705-709 of 1170")
	)
	(layers
		(0 "F.Cu" signal)
		(4 "In1.Cu" signal)
		(6 "In2.Cu" signal)
		(8 "In3.Cu" signal)
		(10 "In4.Cu" jumper)
		(12 "In5.Cu" signal)
		(14 "In6.Cu" signal)
		(16 "In7.Cu" signal)
		(18 "In8.Cu" signal)
		(2 "B.Cu" signal)
		(9 "F.Adhes" user "F.Adhesive")
		(11 "B.Adhes" user "B.Adhesive")
		(13 "F.Paste" user)
		(15 "B.Paste" user)
		(5 "F.SilkS" user "F.Silkscreen")
		(7 "B.SilkS" user "B.Silkscreen")
		(1 "F.Mask" user)
		(3 "B.Mask" user)
		(17 "Dwgs.User" user "User.Drawings")
		(19 "Cmts.User" user "User.Comments")
		(21 "Eco1.User" user "User.Eco1")
		(23 "Eco2.User" user "User.Eco2")
		(25 "Edge.Cuts" user)
		(27 "Margin" user)
		(31 "F.CrtYd" user "F.Courtyard")
		(29 "B.CrtYd" user "B.Courtyard")
		(35 "F.Fab" user)
		(33 "B.Fab" user)
	)
	(footprint "antmicro-footprints:C_0402_1005Metric"
		(layer "B.Cu")
		(at 145.7 81.2)
		(descr "Capacitor SMD 0402")
		(tags "capacitor SMD 0402")
		(property "Reference" "C84"
			(at 1.1 1.5 180)
			(layer "B.SilkS")
			(effects
				(font
					(size 0.7 0.7)
					(thickness 0.15)
				)
				(justify left bottom mirror)
			)
		)
		(property "Value" "C_1u_25V_0402"
			(at -1.022927 -2.155213 180)
			(layer "B.Fab")
			(effects
				(font
					(size 0.7 0.7)
					(thickness 0.15)
				)
				(justify left bottom mirror)
			)
		)
		(property "Datasheet" "https://www.murata.com/products/productdetail?partno=GRM155R61E105KE11%23"
			(at 0 0 180)
			(layer "B.Fab")
			(hide yes)
			(effects
				(font
					(size 1.27 1.27)
					(thickness 0.15)
				)
				(justify mirror)
			)
		)
		(property "Description" "SMD Multilayer Ceramic Capacitor, 1 µF, 25 V, 0402 [1005 Metric], ± 10%, X5R, GRM Series"
			(at 0 0 180)
			(layer "B.Fab")
			(hide yes)
			(effects
				(font
					(size 1.27 1.27)
					(thickness 0.15)
				)
				(justify mirror)
			)
		)
		(property "MPN" "GRM155R61E105KE11J"
			(at 0 0 180)
			(unlocked yes)
			(layer "B.Fab")
			(hide yes)
			(effects
				(font
					(size 1 1)
					(thickness 0.15)
				)
				(justify mirror)
			)
		)
		(property "Manufacturer" "Murata"
			(at 0 0 180)
			(unlocked yes)
			(layer "B.Fab")
			(hide yes)
			(effects
				(font
					(size 1 1)
					(thickness 0.15)
				)
				(justify mirror)
			)
		)
		(property "License" "Apache-2.0"
			(at 0 0 180)
			(unlocked yes)
			(layer "B.Fab")
			(hide yes)
			(effects
				(font
					(size 1 1)
					(thickness 0.15)
				)
				(justify mirror)
			)
		)
		(property "Author" "Antmicro"
			(at 0 0 180)
			(unlocked yes)
			(layer "B.Fab")
			(hide yes)
			(effects
				(font
					(size 1 1)
					(thickness 0.15)
				)
				(justify mirror)
			)
		)
		(property "Val" "1u"
			(at 0 0 180)
			(unlocked yes)
			(layer "B.Fab")
			(hide yes)
			(effects
				(font
					(size 1 1)
					(thickness 0.15)
				)
				(justify mirror)
			)
		)
		(property "Voltage" "25V"
			(at 0 0 180)
			(unlocked yes)
			(layer "B.Fab")
			(hide yes)
			(effects
				(font
					(size 1 1)
					(thickness 0.15)
				)
				(justify mirror)
			)
		)
		(property "Dielectric" "X5R"
			(at 0 0 180)
			(unlocked yes)
			(layer "B.Fab")
			(hide yes)
			(effects
				(font
					(size 1 1)
					(thickness 0.15)
				)
				(justify mirror)
			)
		)
		(sheetname "/SoM_Power/")
		(sheetfile "som_power.kicad_sch")
		(attr smd)
		(fp_rect
			(start -0.925 0.47)
			(end 0.925 -0.47)
			(stroke
				(width 0.05)
				(type default)
			)
			(fill no)
			(layer "B.CrtYd")
		)
		(fp_line
			(start -0.494 -0.248)
			(end -0.494 0.25)
			(stroke
				(width 0.15)
				(type solid)
			)
			(layer "B.Fab")
		)
		(fp_line
			(start -0.494 0.25)
			(end 0.504 0.25)
			(stroke
				(width 0.15)
				(type solid)
			)
			(layer "B.Fab")
		)
		(fp_line
			(start 0.504 -0.248)
			(end -0.494 -0.248)
			(stroke
				(width 0.15)
				(type solid)
			)
			(layer "B.Fab")
		)
		(fp_line
			(start 0.504 0.25)
			(end 0.504 -0.248)
			(stroke
				(width 0.15)
				(type solid)
			)
			(layer "B.Fab")
		)
		(fp_text user "Author: Antmicro"
			(at -0.939 -3.399 180)
			(layer "B.Fab")
			(effects
				(font
					(size 0.7 0.7)
					(thickness 0.15)
				)
				(justify left bottom mirror)
			)
		)
		(fp_text user "${REFERENCE}"
			(at -0.939 -4.599 180)
			(layer "B.Fab")
			(effects
				(font
					(size 0.7 0.7)
					(thickness 0.15)
				)
				(justify left bottom mirror)
			)
		)
		(fp_text user "License: Apache-2.0"
			(at -0.939 -5.799 180)
			(layer "B.Fab")
			(effects
				(font
					(size 0.7 0.7)
					(thickness 0.15)
				)
				(justify left bottom mirror)
			)
		)
		(pad "1" smd roundrect
			(at -0.48 0)
			(size 0.59 0.64)
			(layers "B.Cu" "B.Mask" "B.Paste")
			(roundrect_rratio 0.25)
			(net 1 "GND")
			(pintype "passive")
		)
		(pad "2" smd roundrect
			(at 0.48 0)
			(size 0.59 0.64)
			(layers "B.Cu" "B.Mask" "B.Paste")
			(roundrect_rratio 0.25)
			(net 12 "SYS_VIN_HV")
			(pintype "passive")
		)
	)
	(footprint "antmicro-footprints:C_0603_1608Metric_EIA"
		(layer "B.Cu")
		(at 197.45 127.05)
		(descr "Capacitor SMD 0603, IPC-7351 Density Level A")
		(tags "Capacitor 0603")
		(property "Reference" "C312"
			(at -1.45 -1.65 0)
			(layer "B.SilkS")
			(effects
				(font
					(size 0.7 0.7)
					(thickness 0.15)
				)
				(justify right top mirror)
			)
		)
		(property "Value" "C_22u_16V_0603"
			(at -1.42757 -1.770288 0)
			(layer "B.Fab")
			(effects
				(font
					(size 0.7 0.7)
					(thickness 0.15)
				)
				(justify right top mirror)
			)
		)
		(property "Datasheet" "https://product.samsungsem.com/mlcc/CL10A226MO7JZN.do"
			(at 0 0 0)
			(layer "B.Fab")
			(hide yes)
			(effects
				(font
					(size 1.27 1.27)
					(thickness 0.15)
				)
				(justify mirror)
			)
		)
		(property "Description" "SMD Multilayer Ceramic Capacitor"
			(at 0 0 0)
			(layer "B.Fab")
			(hide yes)
			(effects
				(font
					(size 1.27 1.27)
					(thickness 0.15)
				)
				(justify mirror)
			)
		)
		(property "Manufacturer" "Samsung Electro-Mechanics"
			(at 0 0 180)
			(unlocked yes)
			(layer "B.Fab")
			(hide yes)
			(effects
				(font
					(size 1 1)
					(thickness 0.15)
				)
				(justify mirror)
			)
		)
		(property "MPN" "CL10A226MO7JZNC"
			(at 0 0 180)
			(unlocked yes)
			(layer "B.Fab")
			(hide yes)
			(effects
				(font
					(size 1 1)
					(thickness 0.15)
				)
				(justify mirror)
			)
		)
		(property "Val" "22u"
			(at 0 0 180)
			(unlocked yes)
			(layer "B.Fab")
			(hide yes)
			(effects
				(font
					(size 1 1)
					(thickness 0.15)
				)
				(justify mirror)
			)
		)
		(property "License" "Apache-2.0"
			(at 0 0 180)
			(unlocked yes)
			(layer "B.Fab")
			(hide yes)
			(effects
				(font
					(size 1 1)
					(thickness 0.15)
				)
				(justify mirror)
			)
		)
		(property "Author" "Antmicro"
			(at 0 0 180)
			(unlocked yes)
			(layer "B.Fab")
			(hide yes)
			(effects
				(font
					(size 1 1)
					(thickness 0.15)
				)
				(justify mirror)
			)
		)
		(property "Voltage" "16V"
			(at 0 0 180)
			(unlocked yes)
			(layer "B.Fab")
			(hide yes)
			(effects
				(font
					(size 1 1)
					(thickness 0.15)
				)
				(justify mirror)
			)
		)
		(property "Dielectric" ""
			(at 0 0 180)
			(unlocked yes)
			(layer "B.Fab")
			(hide yes)
			(effects
				(font
					(size 1 1)
					(thickness 0.15)
				)
				(justify mirror)
			)
		)
		(sheetname "/USB Hub/")
		(sheetfile "usb_hub.kicad_sch")
		(attr smd)
		(fp_line
			(start -0.15 -0.55)
			(end 0.15 -0.55)
			(stroke
				(width 0.15)
				(type solid)
			)
			(layer "B.SilkS")
		)
		(fp_line
			(start -0.15 0.55)
			(end 0.15 0.55)
			(stroke
				(width 0.15)
				(type solid)
			)
			(layer "B.SilkS")
		)
		(fp_rect
			(start -1.25 0.65)
			(end 1.25 -0.65)
			(stroke
				(width 0.05)
				(type solid)
			)
			(fill no)
			(layer "B.CrtYd")
		)
		(fp_rect
			(start -0.8 0.45)
			(end 0.8 -0.45)
			(stroke
				(width 0.15)
				(type solid)
			)
			(fill no)
			(layer "B.Fab")
		)
		(fp_text user "${REFERENCE}"
			(at -1.682 -3.895 0)
			(layer "B.Fab")
			(effects
				(font
					(size 0.7 0.7)
					(thickness 0.15)
				)
				(justify right top mirror)
			)
		)
		(fp_text user "License: Apache-2.0"
			(at -1.682 -5.895 0)
			(layer "B.Fab")
			(effects
				(font
					(size 0.7 0.7)
					(thickness 0.15)
				)
				(justify right top mirror)
			)
		)
		(fp_text user "Author: Antmicro"
			(at -1.682 -4.894 0)
			(layer "B.Fab")
			(effects
				(font
					(size 0.7 0.7)
					(thickness 0.15)
				)
				(justify right top mirror)
			)
		)
		(pad "1" smd roundrect
			(at -0.7 0)
			(size 0.8 1.1)
			(layers "B.Cu" "B.Mask" "B.Paste")
			(roundrect_rratio 0.2)
			(net 1 "GND")
			(pintype "passive")
		)
		(pad "2" smd roundrect
			(at 0.7 0)
			(size 0.8 1.1)
			(layers "B.Cu" "B.Mask" "B.Paste")
			(roundrect_rratio 0.2)
			(net 2 "+3V3")
			(pintype "passive")
		)
	)
	(footprint "antmicro-footprints:R_0402_1005Metric"
		(layer "B.Cu")
		(at 233.7 79.6)
		(descr "Resistor SMD 0402")
		(tags "resistor SMD 0402")
		(property "Reference" "R150"
			(at -1.9 -1.3 0)
			(layer "B.SilkS")
			(effects
				(font
					(size 0.7 0.7)
					(thickness 0.15)
				)
				(justify right top mirror)
			)
		)
		(property "Value" "R_10k_0402"
			(at -1.011843 -1.772046 0)
			(layer "B.Fab")
			(effects
				(font
					(size 0.7 0.7)
					(thickness 0.15)
				)
				(justify right top mirror)
			)
		)
		(property "Datasheet" "https://www.bourns.com/docs/product-datasheets/cr.pdf"
			(at 0 0 0)
			(layer "B.Fab")
			(hide yes)
			(effects
				(font
					(size 1.27 1.27)
					(thickness 0.15)
				)
				(justify mirror)
			)
		)
		(property "Description" "SMD Chip Resistor, 10 kohm, ± 1%, 62.5 mW, 0402 [1005 Metric], Thick Film, General Purpose"
			(at 0 0 0)
			(layer "B.Fab")
			(hide yes)
			(effects
				(font
					(size 1.27 1.27)
					(thickness 0.15)
				)
				(justify mirror)
			)
		)
		(property "Manufacturer" "Bourns"
			(at 0 0 180)
			(unlocked yes)
			(layer "B.Fab")
			(hide yes)
			(effects
				(font
					(size 1 1)
					(thickness 0.15)
				)
				(justify mirror)
			)
		)
		(property "MPN" "CR0402-FX-1002GLF"
			(at 0 0 180)
			(unlocked yes)
			(layer "B.Fab")
			(hide yes)
			(effects
				(font
					(size 1 1)
					(thickness 0.15)
				)
				(justify mirror)
			)
		)
		(property "Val" "10k"
			(at 0 0 180)
			(unlocked yes)
			(layer "B.Fab")
			(hide yes)
			(effects
				(font
					(size 1 1)
					(thickness 0.15)
				)
				(justify mirror)
			)
		)
		(property "License" "Apache-2.0"
			(at 0 0 180)
			(unlocked yes)
			(layer "B.Fab")
			(hide yes)
			(effects
				(font
					(size 1 1)
					(thickness 0.15)
				)
				(justify mirror)
			)
		)
		(property "Author" "Antmicro"
			(at 0 0 180)
			(unlocked yes)
			(layer "B.Fab")
			(hide yes)
			(effects
				(font
					(size 1 1)
					(thickness 0.15)
				)
				(justify mirror)
			)
		)
		(property "Tolerance" "1%"
			(at 0 0 180)
			(unlocked yes)
			(layer "B.Fab")
			(hide yes)
			(effects
				(font
					(size 1 1)
					(thickness 0.15)
				)
				(justify mirror)
			)
		)
		(sheetname "/USB Debug, PD/")
		(sheetfile "usb_debug_pd.kicad_sch")
		(attr smd)
		(fp_poly
			(pts
				(xy -0.925 0.47) (xy -0.925 -0.47) (xy 0.925 -0.47) (xy 0.925 0.47)
			)
			(stroke
				(width 0.05)
				(type default)
			)
			(fill no)
			(layer "B.CrtYd")
		)
		(fp_poly
			(pts
				(xy -0.5 0.25) (xy -0.5 -0.25) (xy 0.5 -0.25) (xy 0.5 0.25)
			)
			(stroke
				(width 0.15)
				(type solid)
			)
			(fill no)
			(layer "B.Fab")
		)
		(fp_text user "Author: Antmicro"
			(at -0.95 -4.169 0)
			(layer "B.Fab")
			(effects
				(font
					(size 0.7 0.7)
					(thickness 0.15)
				)
				(justify right top mirror)
			)
		)
		(fp_text user "${REFERENCE}"
			(at -0.95 -3.168 0)
			(layer "B.Fab")
			(effects
				(font
					(size 0.7 0.7)
					(thickness 0.15)
				)
				(justify right top mirror)
			)
		)
		(fp_text user "License: Apache-2.0"
			(at -0.949999 -5.169 0)
			(layer "B.Fab")
			(effects
				(font
					(size 0.7 0.7)
					(thickness 0.15)
				)
				(justify right top mirror)
			)
		)
		(pad "1" smd roundrect
			(at -0.48 0)
			(size 0.59 0.64)
			(layers "B.Cu" "B.Mask" "B.Paste")
			(roundrect_rratio 0.25)
			(net 976 "/USB Debug, PD/USBC0_FLG")
			(pintype "passive")
		)
		(pad "2" smd roundrect
			(at 0.48 0)
			(size 0.59 0.64)
			(layers "B.Cu" "B.Mask" "B.Paste")
			(roundrect_rratio 0.25)
			(net 5 "+5V")
			(pintype "passive")
		)
	)
	(footprint "antmicro-footprints:C_0402_1005Metric"
		(layer "B.Cu")
		(at 199.41 68.02 180)
		(descr "Capacitor SMD 0402")
		(tags "capacitor SMD 0402")
		(property "Reference" "C163"
			(at -1.35 -1.43 0)
			(layer "B.SilkS")
			(effects
				(font
					(size 0.7 0.7)
					(thickness 0.15)
				)
				(justify left bottom mirror)
			)
		)
		(property "Value" "C_100n_0402"
			(at -1.022927 -2.155213 0)
			(layer "B.Fab")
			(effects
				(font
					(size 0.7 0.7)
					(thickness 0.15)
				)
				(justify left bottom mirror)
			)
		)
		(property "Datasheet" "https://www.murata.com/products/productdetail?partno=GRM155R61H104KE14%23"
			(at 0 0 0)
			(layer "B.Fab")
			(hide yes)
			(effects
				(font
					(size 1.27 1.27)
					(thickness 0.15)
				)
				(justify mirror)
			)
		)
		(property "Description" "SMD Multilayer Ceramic Capacitor, 0.1 µF, 50 V, 0402 [1005 Metric], ± 10%, X5R, GRM Series"
			(at 0 0 0)
			(layer "B.Fab")
			(hide yes)
			(effects
				(font
					(size 1.27 1.27)
					(thickness 0.15)
				)
				(justify mirror)
			)
		)
		(property "Manufacturer" "Murata"
			(at 0 0 0)
			(unlocked yes)
			(layer "B.Fab")
			(hide yes)
			(effects
				(font
					(size 1 1)
					(thickness 0.15)
				)
				(justify mirror)
			)
		)
		(property "MPN" "GRM155R61H104KE14D"
			(at 0 0 0)
			(unlocked yes)
			(layer "B.Fab")
			(hide yes)
			(effects
				(font
					(size 1 1)
					(thickness 0.15)
				)
				(justify mirror)
			)
		)
		(property "Val" "100n"
			(at 0 0 0)
			(unlocked yes)
			(layer "B.Fab")
			(hide yes)
			(effects
				(font
					(size 1 1)
					(thickness 0.15)
				)
				(justify mirror)
			)
		)
		(property "License" "Apache-2.0"
			(at 0 0 0)
			(unlocked yes)
			(layer "B.Fab")
			(hide yes)
			(effects
				(font
					(size 1 1)
					(thickness 0.15)
				)
				(justify mirror)
			)
		)
		(property "Author" "Antmicro"
			(at 0 0 0)
			(unlocked yes)
			(layer "B.Fab")
			(hide yes)
			(effects
				(font
					(size 1 1)
					(thickness 0.15)
				)
				(justify mirror)
			)
		)
		(property "Voltage" "50V"
			(at 0 0 0)
			(unlocked yes)
			(layer "B.Fab")
			(hide yes)
			(effects
				(font
					(size 1 1)
					(thickness 0.15)
				)
				(justify mirror)
			)
		)
		(property "Dielectric" "X5R"
			(at 0 0 0)
			(unlocked yes)
			(layer "B.Fab")
			(hide yes)
			(effects
				(font
					(size 1 1)
					(thickness 0.15)
				)
				(justify mirror)
			)
		)
		(sheetname "/CSI/")
		(sheetfile "csi.kicad_sch")
		(attr smd)
		(fp_poly
			(pts
				(xy -0.925 0.47) (xy -0.925 -0.47) (xy 0.925 -0.47) (xy 0.925 0.47)
			)
			(stroke
				(width 0.05)
				(type default)
			)
			(fill no)
			(layer "B.CrtYd")
		)
		(fp_line
			(start 0.504 0.25)
			(end 0.504 -0.248)
			(stroke
				(width 0.15)
				(type solid)
			)
			(layer "B.Fab")
		)
		(fp_line
			(start 0.504 -0.248)
			(end -0.494 -0.248)
			(stroke
				(width 0.15)
				(type solid)
			)
			(layer "B.Fab")
		)
		(fp_line
			(start -0.494 0.25)
			(end 0.504 0.25)
			(stroke
				(width 0.15)
				(type solid)
			)
			(layer "B.Fab")
		)
		(fp_line
			(start -0.494 -0.248)
			(end -0.494 0.25)
			(stroke
				(width 0.15)
				(type solid)
			)
			(layer "B.Fab")
		)
		(fp_text user "${REFERENCE}"
			(at -0.939 -4.599 0)
			(layer "B.Fab")
			(effects
				(font
					(size 0.7 0.7)
					(thickness 0.15)
				)
				(justify left bottom mirror)
			)
		)
		(fp_text user "License: Apache-2.0"
			(at -0.939 -5.799 0)
			(layer "B.Fab")
			(effects
				(font
					(size 0.7 0.7)
					(thickness 0.15)
				)
				(justify left bottom mirror)
			)
		)
		(fp_text user "Author: Antmicro"
			(at -0.939 -3.399 0)
			(layer "B.Fab")
			(effects
				(font
					(size 0.7 0.7)
					(thickness 0.15)
				)
				(justify left bottom mirror)
			)
		)
		(pad "1" smd roundrect
			(at -0.48 0 180)
			(size 0.59 0.64)
			(layers "B.Cu" "B.Mask" "B.Paste")
			(roundrect_rratio 0.25)
			(net 1 "GND")
			(pintype "passive")
		)
		(pad "2" smd roundrect
			(at 0.48 0 180)
			(size 0.59 0.64)
			(layers "B.Cu" "B.Mask" "B.Paste")
			(roundrect_rratio 0.25)
			(net 11 "+1V8")
			(pintype "passive")
		)
	)
	(footprint "antmicro-footprints:R_0402_1005Metric"
		(layer "B.Cu")
		(at 235.7 106.814)
		(descr "Resistor SMD 0402")
		(tags "resistor SMD 0402")
		(property "Reference" "R268"
			(at -2.9 3.786 0)
			(layer "B.SilkS")
			(effects
				(font
					(size 0.7 0.7)
					(thickness 0.15)
				)
				(justify right top mirror)
			)
		)
		(property "Value" "R_0R_0402"
			(at -1.011843 -1.772046 0)
			(layer "B.Fab")
			(effects
				(font
					(size 0.7 0.7)
					(thickness 0.15)
				)
				(justify right top mirror)
			)
		)
		(property "Datasheet" "https://industrial.panasonic.com/cdbs/www-data/pdf/RDA0000/AOA0000C301.pdf"
			(at 0 0 0)
			(layer "B.Fab")
			(hide yes)
			(effects
				(font
					(size 1.27 1.27)
					(thickness 0.15)
				)
				(justify mirror)
			)
		)
		(property "Description" "SMD Chip Resistor, Jumper, 0 ohm, 100 mW, 0402 [1005 Metric], Thick Film, General Purpose"
			(at 0 0 0)
			(layer "B.Fab")
			(hide yes)
			(effects
				(font
					(size 1.27 1.27)
					(thickness 0.15)
				)
				(justify mirror)
			)
		)
		(property "Manufacturer" "Panasonic"
			(at 0 0 180)
			(unlocked yes)
			(layer "B.Fab")
			(hide yes)
			(effects
				(font
					(size 1 1)
					(thickness 0.15)
				)
				(justify mirror)
			)
		)
		(property "MPN" "ERJ2GE0R00X"
			(at 0 0 180)
			(unlocked yes)
			(layer "B.Fab")
			(hide yes)
			(effects
				(font
					(size 1 1)
					(thickness 0.15)
				)
				(justify mirror)
			)
		)
		(property "Val" "0R"
			(at 0 0 180)
			(unlocked yes)
			(layer "B.Fab")
			(hide yes)
			(effects
				(font
					(size 1 1)
					(thickness 0.15)
				)
				(justify mirror)
			)
		)
		(property "License" "Apache-2.0"
			(at 0 0 180)
			(unlocked yes)
			(layer "B.Fab")
			(hide yes)
			(effects
				(font
					(size 1 1)
					(thickness 0.15)
				)
				(justify mirror)
			)
		)
		(property "Author" "Antmicro"
			(at 0 0 180)
			(unlocked yes)
			(layer "B.Fab")
			(hide yes)
			(effects
				(font
					(size 1 1)
					(thickness 0.15)
				)
				(justify mirror)
			)
		)
		(property "Tolerance" "~"
			(at 0 0 180)
			(unlocked yes)
			(layer "B.Fab")
			(hide yes)
			(effects
				(font
					(size 1 1)
					(thickness 0.15)
				)
				(justify mirror)
			)
		)
		(property "Current" "1A"
			(at 0 0 0)
			(unlocked yes)
			(layer "B.Fab")
			(hide yes)
			(effects
				(font
					(size 1 1)
					(thickness 0.15)
				)
				(justify mirror)
			)
		)
		(sheetname "/Recovery USB/")
		(sheetfile "recovery_usb.kicad_sch")
		(attr smd)
		(fp_poly
			(pts
				(xy -0.925 0.47) (xy -0.925 -0.47) (xy 0.925 -0.47) (xy 0.925 0.47)
			)
			(stroke
				(width 0.05)
				(type default)
			)
			(fill no)
			(layer "B.CrtYd")
		)
		(fp_poly
			(pts
				(xy -0.5 0.25) (xy -0.5 -0.25) (xy 0.5 -0.25) (xy 0.5 0.25)
			)
			(stroke
				(width 0.15)
				(type solid)
			)
			(fill no)
			(layer "B.Fab")
		)
		(fp_text user "${REFERENCE}"
			(at -0.95 -3.168 0)
			(layer "B.Fab")
			(effects
				(font
					(size 0.7 0.7)
					(thickness 0.15)
				)
				(justify right top mirror)
			)
		)
		(fp_text user "Author: Antmicro"
			(at -0.95 -4.169 0)
			(layer "B.Fab")
			(effects
				(font
					(size 0.7 0.7)
					(thickness 0.15)
				)
				(justify right top mirror)
			)
		)
		(fp_text user "License: Apache-2.0"
			(at -0.949999 -5.169 0)
			(layer "B.Fab")
			(effects
				(font
					(size 0.7 0.7)
					(thickness 0.15)
				)
				(justify right top mirror)
			)
		)
		(pad "1" smd roundrect
			(at -0.48 0)
			(size 0.59 0.64)
			(layers "B.Cu" "B.Mask" "B.Paste")
			(roundrect_rratio 0.25)
			(net 890 "Net-(Q19-D)")
			(pintype "passive")
		)
		(pad "2" smd roundrect
			(at 0.48 0)
			(size 0.59 0.64)
			(layers "B.Cu" "B.Mask" "B.Paste")
			(roundrect_rratio 0.25)
			(net 1243 "Net-(U23-FLG)")
			(pintype "passive")
		)
	)
)
